# S9S_MB_2U (Grand Teton) — schematic netlist excerpt (pin names and nets, part order shuffled) for the footprints in the layout excerpt that follows; sources: Cadence DE-HDL packaged netlist, KiCad conversion of 03242023_DA0F0TMBIJ0_F0T_Motherboard_J_brd_V01_OCP.brd

PC531  Q_CAP  100NF 50V 10% X7R  pkg C0402  page 286 : A = SW_PVCCIN_CPU1_BOOT4_R ; B = SW_PVCCIN_CPU1_BOOTR4
PC1197  Q_CAP  100NF 50V 10% X7R  pkg C0402  page 290 : A = SW_PVCCFA_EHV_FIVRA_CPU1_BOOT3_ ; B = SW_PVCCFA_EHV_FIVRA_CPU1_BOOTR3

(kicad_pcb
	(version 20260206)
	(generator "pcbnew")
	(generator_version "10.0")
	(general
		(thickness 1.6)
		(legacy_teardrops no)
	)
	(paper "A4")
	(title_block
		(title "03242023_DA0F0TMBIJ0_F0T_Motherboard_J_brd_V01_OCP.brd")
		(comment 1 "Grand Teton / footprints 1123-1124 of 6105")
	)
	(layers
		(0 "F.Cu" signal "TOP")
		(4 "In1.Cu" signal "GND")
		(6 "In2.Cu" signal "IN1")
		(8 "In3.Cu" signal "GND1")
		(10 "In4.Cu" signal "IN2")
		(12 "In5.Cu" signal "GND2")
		(14 "In6.Cu" signal "IN3")
		(16 "In7.Cu" signal "GND3")
		(18 "In8.Cu" signal "VCC")
		(20 "In9.Cu" signal "VCC1")
		(22 "In10.Cu" signal "GND4")
		(24 "In11.Cu" signal "IN4")
		(26 "In12.Cu" signal "GND5")
		(28 "In13.Cu" signal "IN5")
		(30 "In14.Cu" signal "GND6")
		(32 "In15.Cu" signal "IN6")
		(34 "In16.Cu" signal "GND7")
		(2 "B.Cu" signal "BOTTOM")
		(9 "F.Adhes" user "F.Adhesive")
		(11 "B.Adhes" user "B.Adhesive")
		(13 "F.Paste" user "Package Geometry/Pastemask Top")
		(15 "B.Paste" user "Package Geometry/Pastemask Bottom")
		(5 "F.SilkS" user "Ref Des/Silkscreen Top")
		(7 "B.SilkS" user "Ref Des/Silkscreen Bottom")
		(1 "F.Mask" user "Board Geometry/Soldermask Top")
		(3 "B.Mask" user "Board Geometry/Soldermask Bottom")
		(17 "Dwgs.User" user "User.Drawings")
		(19 "Cmts.User" user "User.Comments")
		(21 "Eco1.User" user "User.Eco1")
		(23 "Eco2.User" user "User.Eco2")
		(25 "Edge.Cuts" user "Board Geometry/Outline")
		(27 "Margin" user)
		(31 "F.CrtYd" user "Package Geometry/Place Bound Top")
		(29 "B.CrtYd" user "Package Geometry/Place Bound Bottom")
		(35 "F.Fab" user "Ref Des/Assembly Top")
		(33 "B.Fab" user "Ref Des/Assembly Bottom")
	)
	(footprint ""
		(layer "F.Cu")
		(at 123.265184 -338.17814 -90)
		(property "Reference" "PC531"
			(at 0 0 270)
			(layer "F.SilkS")
			(hide yes)
			(effects
				(font
					(size 1.27 1.27)
				)
			)
		)
		(property "Value" ""
			(at 0 0 270)
			(layer "F.Fab")
			(effects
				(font
					(size 1.27 1.27)
				)
			)
		)
		(duplicate_pad_numbers_are_jumpers no)
		(fp_line
			(start -0.7874 0.4064)
			(end -0.7874 -0.4064)
			(stroke
				(width 0.1524)
				(type default)
			)
			(layer "F.SilkS")
		)
		(fp_line
			(start 0.7874 0.4064)
			(end -0.7874 0.4064)
			(stroke
				(width 0.1524)
				(type default)
			)
			(layer "F.SilkS")
		)
		(fp_line
			(start -0.7874 -0.4064)
			(end 0.7874 -0.4064)
			(stroke
				(width 0.1524)
				(type default)
			)
			(layer "F.SilkS")
		)
		(fp_line
			(start 0.7874 -0.4064)
			(end 0.7874 0.4064)
			(stroke
				(width 0.1524)
				(type default)
			)
			(layer "F.SilkS")
		)
		(fp_line
			(start -0.67945 0.3048)
			(end -0.67945 -0.305054)
			(stroke
				(width 0.1)
				(type default)
			)
			(layer "F.Fab")
		)
		(fp_line
			(start -0.12065 0.3048)
			(end -0.67945 0.3048)
			(stroke
				(width 0.1)
				(type default)
			)
			(layer "F.Fab")
		)
		(fp_line
			(start 0.120396 0.3048)
			(end 0.120396 0.2794)
			(stroke
				(width 0.1)
				(type default)
			)
			(layer "F.Fab")
		)
		(fp_line
			(start 0.67945 0.3048)
			(end 0.120396 0.3048)
			(stroke
				(width 0.1)
				(type default)
			)
			(layer "F.Fab")
		)
		(fp_line
			(start -0.12065 0.2794)
			(end -0.12065 0.3048)
			(stroke
				(width 0.1)
				(type default)
			)
			(layer "F.Fab")
		)
		(fp_line
			(start 0.120396 0.2794)
			(end -0.12065 0.2794)
			(stroke
				(width 0.1)
				(type default)
			)
			(layer "F.Fab")
		)
		(fp_line
			(start -0.12065 -0.2794)
			(end 0.12065 -0.2794)
			(stroke
				(width 0.1)
				(type default)
			)
			(layer "F.Fab")
		)
		(fp_line
			(start 0.12065 -0.2794)
			(end 0.12065 -0.3048)
			(stroke
				(width 0.1)
				(type default)
			)
			(layer "F.Fab")
		)
		(fp_line
			(start 0.12065 -0.3048)
			(end 0.67945 -0.3048)
			(stroke
				(width 0.1)
				(type default)
			)
			(layer "F.Fab")
		)
		(fp_line
			(start 0.67945 -0.3048)
			(end 0.67945 0.3048)
			(stroke
				(width 0.1)
				(type default)
			)
			(layer "F.Fab")
		)
		(fp_line
			(start -0.67945 -0.305054)
			(end -0.12065 -0.305054)
			(stroke
				(width 0.1)
				(type default)
			)
			(layer "F.Fab")
		)
		(fp_line
			(start -0.12065 -0.305054)
			(end -0.12065 -0.2794)
			(stroke
				(width 0.1)
				(type default)
			)
			(layer "F.Fab")
		)
		(pad "1" smd circle
			(at -0.40005 0 270)
			(size 0 0)
			(layers "F.Cu" "F.Mask" "F.Paste")
			(net "SW_PVCCIN_CPU1_BOOT4_R")
		)
		(pad "2" smd circle
			(at 0.40005 0 270)
			(size 0 0)
			(layers "F.Cu" "F.Mask" "F.Paste")
			(net "SW_PVCCIN_CPU1_BOOTR4")
		)
	)
	(footprint ""
		(layer "F.Cu")
		(at 183.49849 -358.15778 -90)
		(property "Reference" "PC1197"
			(at 0 0 270)
			(layer "F.SilkS")
			(hide yes)
			(effects
				(font
					(size 1.27 1.27)
				)
			)
		)
		(property "Value" ""
			(at 0 0 270)
			(layer "F.Fab")
			(effects
				(font
					(size 1.27 1.27)
				)
			)
		)
		(duplicate_pad_numbers_are_jumpers no)
		(fp_line
			(start -0.7874 0.4064)
			(end -0.7874 -0.4064)
			(stroke
				(width 0.1524)
				(type default)
			)
			(layer "F.SilkS")
		)
		(fp_line
			(start 0.7874 0.4064)
			(end -0.7874 0.4064)
			(stroke
				(width 0.1524)
				(type default)
			)
			(layer "F.SilkS")
		)
		(fp_line
			(start -0.7874 -0.4064)
			(end 0.7874 -0.4064)
			(stroke
				(width 0.1524)
				(type default)
			)
			(layer "F.SilkS")
		)
		(fp_line
			(start 0.7874 -0.4064)
			(end 0.7874 0.4064)
			(stroke
				(width 0.1524)
				(type default)
			)
			(layer "F.SilkS")
		)
		(fp_line
			(start -0.67945 0.3048)
			(end -0.67945 -0.305054)
			(stroke
				(width 0.1)
				(type default)
			)
			(layer "F.Fab")
		)
		(fp_line
			(start -0.12065 0.3048)
			(end -0.67945 0.3048)
			(stroke
				(width 0.1)
				(type default)
			)
			(layer "F.Fab")
		)
		(fp_line
			(start 0.120396 0.3048)
			(end 0.120396 0.2794)
			(stroke
				(width 0.1)
				(type default)
			)
			(layer "F.Fab")
		)
		(fp_line
			(start 0.67945 0.3048)
			(end 0.120396 0.3048)
			(stroke
				(width 0.1)
				(type default)
			)
			(layer "F.Fab")
		)
		(fp_line
			(start -0.12065 0.2794)
			(end -0.12065 0.3048)
			(stroke
				(width 0.1)
				(type default)
			)
			(layer "F.Fab")
		)
		(fp_line
			(start 0.120396 0.2794)
			(end -0.12065 0.2794)
			(stroke
				(width 0.1)
				(type default)
			)
			(layer "F.Fab")
		)
		(fp_line
			(start -0.12065 -0.2794)
			(end 0.12065 -0.2794)
			(stroke
				(width 0.1)
				(type default)
			)
			(layer "F.Fab")
		)
		(fp_line
			(start 0.12065 -0.2794)
			(end 0.12065 -0.3048)
			(stroke
				(width 0.1)
				(type default)
			)
			(layer "F.Fab")
		)
		(fp_line
			(start 0.12065 -0.3048)
			(end 0.67945 -0.3048)
			(stroke
				(width 0.1)
				(type default)
			)
			(layer "F.Fab")
		)
		(fp_line
			(start 0.67945 -0.3048)
			(end 0.67945 0.3048)
			(stroke
				(width 0.1)
				(type default)
			)
			(layer "F.Fab")
		)
		(fp_line
			(start -0.67945 -0.305054)
			(end -0.12065 -0.305054)
			(stroke
				(width 0.1)
				(type default)
			)
			(layer "F.Fab")
		)
		(fp_line
			(start -0.12065 -0.305054)
			(end -0.12065 -0.2794)
			(stroke
				(width 0.1)
				(type default)
			)
			(layer "F.Fab")
		)
		(pad "1" smd circle
			(at -0.40005 0 270)
			(size 0 0)
			(layers "F.Cu" "F.Mask" "F.Paste")
			(net "SW_PVCCFA_EHV_FIVRA_CPU1_BOOT3_")
		)
		(pad "2" smd circle
			(at 0.40005 0 270)
			(size 0 0)
			(layers "F.Cu" "F.Mask" "F.Paste")
			(net "SW_PVCCFA_EHV_FIVRA_CPU1_BOOTR3")
		)
	)
)
